(kicad_pcb
	(version 20260206)
	(generator "pcbnew")
	(generator_version "10.0")
	(general
		(thickness 1.6)
		(legacy_teardrops no)
	)
	(paper "A4")
	(title_block
		(title "netronome-mezz — pcbd0082-001_rev01_jul9_a.brd")
		(comment 1 "Open CloudServer (Microsoft) / footprints 25-32 of 714")
	)
	(layers
		(0 "F.Cu" signal "TOP")
		(4 "In1.Cu" signal "02_GND")
		(6 "In2.Cu" signal "03_SIG")
		(8 "In3.Cu" signal "04_SIG")
		(10 "In4.Cu" signal "05_GND")
		(12 "In5.Cu" signal "06_PWR1")
		(14 "In6.Cu" signal "07_SIG")
		(16 "In7.Cu" signal "08_SIG")
		(18 "In8.Cu" signal "09_GND")
		(2 "B.Cu" signal "BOTTOM")
		(9 "F.Adhes" user "F.Adhesive")
		(11 "B.Adhes" user "B.Adhesive")
		(13 "F.Paste" user "Package Geometry/Pastemask Top")
		(15 "B.Paste" user "Package Geometry/Pastemask Bottom")
		(5 "F.SilkS" user "Ref Des/Silkscreen Top")
		(7 "B.SilkS" user "Ref Des/Silkscreen Bottom")
		(1 "F.Mask" user "Board Geometry/Soldermask Top")
		(3 "B.Mask" user "Board Geometry/Soldermask Bottom")
		(17 "Dwgs.User" user "User.Drawings")
		(19 "Cmts.User" user "User.Comments")
		(21 "Eco1.User" user "User.Eco1")
		(23 "Eco2.User" user "User.Eco2")
		(25 "Edge.Cuts" user "Board Geometry/Outline")
		(27 "Margin" user)
		(31 "F.CrtYd" user "Package Geometry/Place Bound Top")
		(29 "B.CrtYd" user "Package Geometry/Place Bound Bottom")
		(35 "F.Fab" user "Ref Des/Assembly Top")
		(33 "B.Fab" user "Ref Des/Assembly Bottom")
		(45 "User.4" user "COMPVAL_TYPE_BOTTOM")
	)
	(footprint ""
		(layer "F.Cu")
		(at 20.193 40.132)
		(property "Reference" "C21"
			(at 1.04267 1.143 90)
			(unlocked yes)
			(layer "F.SilkS")
			(effects
				(font
					(size 0.7874 0.5842)
					(thickness 0.127)
				)
				(justify left)
			)
		)
		(property "Value" "22UF"
			(at -0.148158 1.7526 90)
			(unlocked yes)
			(layer "F.Fab")
			(hide yes)
			(effects
				(font
					(size 1.27 0.9652)
					(thickness 0.000001)
				)
				(justify left)
			)
		)
		(property "Device Type" "CAPC0063"
			(at -0.148158 1.7526 90)
			(unlocked yes)
			(layer "F.Fab")
			(hide yes)
			(effects
				(font
					(size 1.27 0.9652)
					(thickness 0.000001)
				)
				(justify left)
			)
		)
		(duplicate_pad_numbers_are_jumpers no)
		(fp_circle
			(center 0 0)
			(end 0.127 0)
			(stroke
				(width 0.2032)
				(type default)
			)
			(fill no)
			(layer "F.SilkS")
		)
		(fp_poly
			(pts
				(xy 0.7874 -1.6637) (xy -0.7874 -1.6637) (xy -0.7874 1.6637) (xy 0.7874 1.6637)
			)
			(stroke
				(width 0)
				(type default)
			)
			(fill no)
			(layer "F.CrtYd")
		)
		(fp_line
			(start -0.4064 -0.7874)
			(end 0.4064 -0.7874)
			(stroke
				(width 0.0254)
				(type default)
			)
			(layer "F.Fab")
		)
		(fp_line
			(start -0.4064 0.8128)
			(end -0.4064 -0.7874)
			(stroke
				(width 0.0254)
				(type default)
			)
			(layer "F.Fab")
		)
		(fp_line
			(start 0.4064 -0.7874)
			(end 0.4064 0.8128)
			(stroke
				(width 0.0254)
				(type default)
			)
			(layer "F.Fab")
		)
		(fp_line
			(start 0.4064 0.8128)
			(end -0.4064 0.8128)
			(stroke
				(width 0.0254)
				(type default)
			)
			(layer "F.Fab")
		)
		(pad "1" smd rect
			(at 0 -0.8001)
			(size 0.8636 0.9652)
			(layers "F.Cu" "F.Mask" "F.Paste")
			(net "DDR_1.8V")
		)
		(pad "2" smd rect
			(at 0 0.8001)
			(size 0.8636 0.9652)
			(layers "F.Cu" "F.Mask" "F.Paste")
			(net "GND")
		)
		(zone
			(layer "F.Cu")
			(hatch none 0.5)
			(connect_pads
				(clearance 0)
			)
			(min_thickness 0.25)
			(keepout
				(tracks not_allowed)
				(vias allowed)
				(pads allowed)
				(copperpour not_allowed)
				(footprints allowed)
			)
			(placement
				(enabled no)
				(sheetname "")
			)
			(fill
				(thermal_gap 0.5)
				(thermal_bridge_width 0.5)
				(island_removal_mode 0)
			)
			(polygon
				(pts
					(xy 20.1295 39.878) (xy 20.2565 39.878) (xy 20.2565 40.386) (xy 20.1295 40.386)
				)
			)
		)
	)
	(footprint ""
		(layer "F.Cu")
		(at 9.017 41.3512 180)
		(property "Reference" "C22"
			(at -0.508 -0.53467 0)
			(unlocked yes)
			(layer "F.SilkS")
			(effects
				(font
					(size 0.7874 0.5842)
					(thickness 0.127)
				)
				(justify left)
			)
		)
		(property "Value" "22UF"
			(at -0.148158 1.7526 270)
			(unlocked yes)
			(layer "F.Fab")
			(hide yes)
			(effects
				(font
					(size 1.27 0.9652)
					(thickness 0.000001)
				)
				(justify left)
			)
		)
		(property "Device Type" "CAPC0063"
			(at -0.148158 1.7526 270)
			(unlocked yes)
			(layer "F.Fab")
			(hide yes)
			(effects
				(font
					(size 1.27 0.9652)
					(thickness 0.000001)
				)
				(justify left)
			)
		)
		(duplicate_pad_numbers_are_jumpers no)
		(fp_circle
			(center 0 0)
			(end -0.127 0)
			(stroke
				(width 0.2032)
				(type default)
			)
			(fill no)
			(layer "F.SilkS")
		)
		(fp_poly
			(pts
				(xy 0.658419 -1.6637) (xy -0.7874 -1.6637) (xy -0.7874 1.6637) (xy 0.658419 1.6637)
			)
			(stroke
				(width 0)
				(type default)
			)
			(fill no)
			(layer "F.CrtYd")
		)
		(fp_line
			(start 0.4064 0.8128)
			(end -0.4064 0.8128)
			(stroke
				(width 0.0254)
				(type default)
			)
			(layer "F.Fab")
		)
		(fp_line
			(start 0.4064 -0.7874)
			(end 0.4064 0.8128)
			(stroke
				(width 0.0254)
				(type default)
			)
			(layer "F.Fab")
		)
		(fp_line
			(start -0.4064 0.8128)
			(end -0.4064 -0.7874)
			(stroke
				(width 0.0254)
				(type default)
			)
			(layer "F.Fab")
		)
		(fp_line
			(start -0.4064 -0.7874)
			(end 0.4064 -0.7874)
			(stroke
				(width 0.0254)
				(type default)
			)
			(layer "F.Fab")
		)
		(pad "1" smd rect
			(at 0 -0.8001 180)
			(size 0.8636 0.9652)
			(layers "F.Cu" "F.Mask" "F.Paste")
			(net "VDD_1.5V")
		)
		(pad "2" smd rect
			(at 0 0.8001 180)
			(size 0.8636 0.9652)
			(layers "F.Cu" "F.Mask" "F.Paste")
			(net "GND")
		)
		(zone
			(layer "F.Cu")
			(hatch none 0.5)
			(connect_pads
				(clearance 0)
			)
			(min_thickness 0.25)
			(keepout
				(tracks not_allowed)
				(vias allowed)
				(pads allowed)
				(copperpour not_allowed)
				(footprints allowed)
			)
			(placement
				(enabled no)
				(sheetname "")
			)
			(fill
				(thermal_gap 0.5)
				(thermal_bridge_width 0.5)
				(island_removal_mode 0)
			)
			(polygon
				(pts
					(xy 9.0805 41.6052) (xy 8.9535 41.6052) (xy 8.9535 41.0972) (xy 9.0805 41.0972)
				)
			)
		)
	)
	(footprint ""
		(layer "F.Cu")
		(at 82.804 32.576414)
		(property "Reference" "R210"
			(at 0 0 0)
			(layer "F.SilkS")
			(hide yes)
			(effects
				(font
					(size 1.27 1.27)
				)
			)
		)
		(property "Value" "39.0"
			(at -0.148158 1.3462 90)
			(unlocked yes)
			(layer "F.Fab")
			(hide yes)
			(effects
				(font
					(size 1.27 0.9652)
					(thickness 0.000001)
				)
				(justify left)
			)
		)
		(property "Device Type" "REST0108"
			(at -0.148158 1.3462 90)
			(unlocked yes)
			(layer "F.Fab")
			(hide yes)
			(effects
				(font
					(size 1.27 0.9652)
					(thickness 0.000001)
				)
				(justify left)
			)
		)
		(duplicate_pad_numbers_are_jumpers no)
		(fp_poly
			(pts
				(xy 0.635 1.0668) (xy 0.635 -1.0668) (xy -0.635 -1.0668) (xy -0.635 1.0668)
			)
			(stroke
				(width 0)
				(type default)
			)
			(fill no)
			(layer "F.CrtYd")
		)
		(fp_line
			(start -0.254 -0.508)
			(end 0.254 -0.508)
			(stroke
				(width 0.0254)
				(type default)
			)
			(layer "F.Fab")
		)
		(fp_line
			(start -0.254 0.508)
			(end -0.254 -0.508)
			(stroke
				(width 0.0254)
				(type default)
			)
			(layer "F.Fab")
		)
		(fp_line
			(start 0.254 -0.508)
			(end 0.254 0.508)
			(stroke
				(width 0.0254)
				(type default)
			)
			(layer "F.Fab")
		)
		(fp_line
			(start 0.254 0.508)
			(end -0.254 0.508)
			(stroke
				(width 0.0254)
				(type default)
			)
			(layer "F.Fab")
		)
		(pad "1" smd rect
			(at 0 -0.4191)
			(size 0.508 0.5334)
			(layers "F.Cu" "F.Mask" "F.Paste")
			(net "DDR0_32A_A4")
		)
		(pad "2" smd rect
			(at 0 0.4191)
			(size 0.508 0.5334)
			(layers "F.Cu" "F.Mask" "F.Paste")
			(net "DDR_VTT")
		)
		(zone
			(layer "F.Cu")
			(hatch none 0.5)
			(connect_pads
				(clearance 0)
			)
			(min_thickness 0.25)
			(keepout
				(tracks not_allowed)
				(vias allowed)
				(pads allowed)
				(copperpour not_allowed)
				(footprints allowed)
			)
			(placement
				(enabled no)
				(sheetname "")
			)
			(fill
				(thermal_gap 0.5)
				(thermal_bridge_width 0.5)
				(island_removal_mode 0)
			)
			(polygon
				(pts
					(xy 82.8294 32.551014) (xy 82.8294 32.601814) (xy 82.7786 32.601814) (xy 82.7786 32.551014)
				)
			)
		)
	)
	(footprint ""
		(layer "F.Cu")
		(at 31.369 43.942)
		(property "Reference" "R182"
			(at 0 0 0)
			(layer "F.SilkS")
			(hide yes)
			(effects
				(font
					(size 1.27 1.27)
				)
			)
		)
		(property "Value" "0"
			(at -0.148158 1.3462 90)
			(unlocked yes)
			(layer "F.Fab")
			(hide yes)
			(effects
				(font
					(size 1.27 0.9652)
					(thickness 0.000001)
				)
				(justify left)
			)
		)
		(property "Device Type" "REST1111"
			(at -0.148158 1.3462 90)
			(unlocked yes)
			(layer "F.Fab")
			(hide yes)
			(effects
				(font
					(size 1.27 0.9652)
					(thickness 0.000001)
				)
				(justify left)
			)
		)
		(duplicate_pad_numbers_are_jumpers no)
		(fp_poly
			(pts
				(xy 0.635 1.0668) (xy 0.635 -1.0668) (xy -0.635 -1.0668) (xy -0.635 1.0668)
			)
			(stroke
				(width 0)
				(type default)
			)
			(fill no)
			(layer "F.CrtYd")
		)
		(fp_line
			(start -0.254 -0.508)
			(end 0.254 -0.508)
			(stroke
				(width 0.0254)
				(type default)
			)
			(layer "F.Fab")
		)
		(fp_line
			(start -0.254 0.508)
			(end -0.254 -0.508)
			(stroke
				(width 0.0254)
				(type default)
			)
			(layer "F.Fab")
		)
		(fp_line
			(start 0.254 -0.508)
			(end 0.254 0.508)
			(stroke
				(width 0.0254)
				(type default)
			)
			(layer "F.Fab")
		)
		(fp_line
			(start 0.254 0.508)
			(end -0.254 0.508)
			(stroke
				(width 0.0254)
				(type default)
			)
			(layer "F.Fab")
		)
		(pad "1" smd rect
			(at 0 -0.4191)
			(size 0.508 0.5334)
			(layers "F.Cu" "F.Mask" "F.Paste")
			(net "10N2385")
		)
		(pad "2" smd rect
			(at 0 0.4191)
			(size 0.508 0.5334)
			(layers "F.Cu" "F.Mask" "F.Paste")
			(net "NFP_VDD_CORE_SENSE_VDD")
		)
		(zone
			(layer "F.Cu")
			(hatch none 0.5)
			(connect_pads
				(clearance 0)
			)
			(min_thickness 0.25)
			(keepout
				(tracks not_allowed)
				(vias allowed)
				(pads allowed)
				(copperpour not_allowed)
				(footprints allowed)
			)
			(placement
				(enabled no)
				(sheetname "")
			)
			(fill
				(thermal_gap 0.5)
				(thermal_bridge_width 0.5)
				(island_removal_mode 0)
			)
			(polygon
				(pts
					(xy 31.3944 43.9166) (xy 31.3944 43.9674) (xy 31.3436 43.9674) (xy 31.3436 43.9166)
				)
			)
		)
	)
	(footprint ""
		(layer "F.Cu")
		(at 84.6836 40.64)
		(property "Reference" "R108"
			(at 0.4064 -0.73533 0)
			(unlocked yes)
			(layer "F.SilkS")
			(effects
				(font
					(size 0.7874 0.5842)
					(thickness 0.127)
				)
				(justify left)
			)
		)
		(property "Value" "2.2"
			(at -0.148158 1.3462 90)
			(unlocked yes)
			(layer "F.Fab")
			(hide yes)
			(effects
				(font
					(size 1.27 0.9652)
					(thickness 0.000001)
				)
				(justify left)
			)
		)
		(property "Device Type" "REST0114"
			(at -0.148158 1.3462 90)
			(unlocked yes)
			(layer "F.Fab")
			(hide yes)
			(effects
				(font
					(size 1.27 0.9652)
					(thickness 0.000001)
				)
				(justify left)
			)
		)
		(duplicate_pad_numbers_are_jumpers no)
		(fp_poly
			(pts
				(xy 0.635 1.0668) (xy 0.635 -1.0668) (xy -0.635 -1.0668) (xy -0.635 1.0668)
			)
			(stroke
				(width 0)
				(type default)
			)
			(fill no)
			(layer "F.CrtYd")
		)
		(fp_line
			(start -0.254 -0.508)
			(end 0.254 -0.508)
			(stroke
				(width 0.0254)
				(type default)
			)
			(layer "F.Fab")
		)
		(fp_line
			(start -0.254 0.508)
			(end -0.254 -0.508)
			(stroke
				(width 0.0254)
				(type default)
			)
			(layer "F.Fab")
		)
		(fp_line
			(start 0.254 -0.508)
			(end 0.254 0.508)
			(stroke
				(width 0.0254)
				(type default)
			)
			(layer "F.Fab")
		)
		(fp_line
			(start 0.254 0.508)
			(end -0.254 0.508)
			(stroke
				(width 0.0254)
				(type default)
			)
			(layer "F.Fab")
		)
		(pad "1" smd rect
			(at 0 -0.4191)
			(size 0.508 0.5334)
			(layers "F.Cu" "F.Mask" "F.Paste")
			(net "11N2179")
		)
		(pad "2" smd rect
			(at 0 0.4191)
			(size 0.508 0.5334)
			(layers "F.Cu" "F.Mask" "F.Paste")
			(net "11N2181")
		)
		(zone
			(layer "F.Cu")
			(hatch none 0.5)
			(connect_pads
				(clearance 0)
			)
			(min_thickness 0.25)
			(keepout
				(tracks not_allowed)
				(vias allowed)
				(pads allowed)
				(copperpour not_allowed)
				(footprints allowed)
			)
			(placement
				(enabled no)
				(sheetname "")
			)
			(fill
				(thermal_gap 0.5)
				(thermal_bridge_width 0.5)
				(island_removal_mode 0)
			)
			(polygon
				(pts
					(xy 84.709 40.6146) (xy 84.709 40.6654) (xy 84.6582 40.6654) (xy 84.6582 40.6146)
				)
			)
		)
	)
	(footprint ""
		(layer "F.Cu")
		(at 82.7278 22.987 180)
		(property "Reference" "R209"
			(at 0 0 180)
			(layer "F.SilkS")
			(hide yes)
			(effects
				(font
					(size 1.27 1.27)
				)
			)
		)
		(property "Value" "39.0"
			(at -0.148158 1.3462 270)
			(unlocked yes)
			(layer "F.Fab")
			(hide yes)
			(effects
				(font
					(size 1.27 0.9652)
					(thickness 0.000001)
				)
				(justify left)
			)
		)
		(property "Device Type" "REST0108"
			(at -0.148158 1.3462 270)
			(unlocked yes)
			(layer "F.Fab")
			(hide yes)
			(effects
				(font
					(size 1.27 0.9652)
					(thickness 0.000001)
				)
				(justify left)
			)
		)
		(duplicate_pad_numbers_are_jumpers no)
		(fp_poly
			(pts
				(xy 0.635 1.0668) (xy 0.635 -1.0668) (xy -0.635 -1.0668) (xy -0.635 1.0668)
			)
			(stroke
				(width 0)
				(type default)
			)
			(fill no)
			(layer "F.CrtYd")
		)
		(fp_line
			(start 0.254 0.508)
			(end -0.254 0.508)
			(stroke
				(width 0.0254)
				(type default)
			)
			(layer "F.Fab")
		)
		(fp_line
			(start 0.254 -0.508)
			(end 0.254 0.508)
			(stroke
				(width 0.0254)
				(type default)
			)
			(layer "F.Fab")
		)
		(fp_line
			(start -0.254 0.508)
			(end -0.254 -0.508)
			(stroke
				(width 0.0254)
				(type default)
			)
			(layer "F.Fab")
		)
		(fp_line
			(start -0.254 -0.508)
			(end 0.254 -0.508)
			(stroke
				(width 0.0254)
				(type default)
			)
			(layer "F.Fab")
		)
		(pad "1" smd rect
			(at 0 -0.4191 180)
			(size 0.508 0.5334)
			(layers "F.Cu" "F.Mask" "F.Paste")
			(net "DDR0_32A_A3")
		)
		(pad "2" smd rect
			(at 0 0.4191 180)
			(size 0.508 0.5334)
			(layers "F.Cu" "F.Mask" "F.Paste")
			(net "DDR_VTT")
		)
		(zone
			(layer "F.Cu")
			(hatch none 0.5)
			(connect_pads
				(clearance 0)
			)
			(min_thickness 0.25)
			(keepout
				(tracks not_allowed)
				(vias allowed)
				(pads allowed)
				(copperpour not_allowed)
				(footprints allowed)
			)
			(placement
				(enabled no)
				(sheetname "")
			)
			(fill
				(thermal_gap 0.5)
				(thermal_bridge_width 0.5)
				(island_removal_mode 0)
			)
			(polygon
				(pts
					(xy 82.7024 23.0124) (xy 82.7024 22.9616) (xy 82.7532 22.9616) (xy 82.7532 23.0124)
				)
			)
		)
	)
	(footprint ""
		(layer "F.Cu")
		(at 82.804 28.702 180)
		(property "Reference" "R207"
			(at 0 0 180)
			(layer "F.SilkS")
			(hide yes)
			(effects
				(font
					(size 1.27 1.27)
				)
			)
		)
		(property "Value" "39.0"
			(at -0.148158 1.3462 270)
			(unlocked yes)
			(layer "F.Fab")
			(hide yes)
			(effects
				(font
					(size 1.27 0.9652)
					(thickness 0.000001)
				)
				(justify left)
			)
		)
		(property "Device Type" "REST0108"
			(at -0.148158 1.3462 270)
			(unlocked yes)
			(layer "F.Fab")
			(hide yes)
			(effects
				(font
					(size 1.27 0.9652)
					(thickness 0.000001)
				)
				(justify left)
			)
		)
		(duplicate_pad_numbers_are_jumpers no)
		(fp_poly
			(pts
				(xy 0.635 1.0668) (xy 0.635 -1.0668) (xy -0.635 -1.0668) (xy -0.635 1.0668)
			)
			(stroke
				(width 0)
				(type default)
			)
			(fill no)
			(layer "F.CrtYd")
		)
		(fp_line
			(start 0.254 0.508)
			(end -0.254 0.508)
			(stroke
				(width 0.0254)
				(type default)
			)
			(layer "F.Fab")
		)
		(fp_line
			(start 0.254 -0.508)
			(end 0.254 0.508)
			(stroke
				(width 0.0254)
				(type default)
			)
			(layer "F.Fab")
		)
		(fp_line
			(start -0.254 0.508)
			(end -0.254 -0.508)
			(stroke
				(width 0.0254)
				(type default)
			)
			(layer "F.Fab")
		)
		(fp_line
			(start -0.254 -0.508)
			(end 0.254 -0.508)
			(stroke
				(width 0.0254)
				(type default)
			)
			(layer "F.Fab")
		)
		(pad "1" smd rect
			(at 0 -0.4191 180)
			(size 0.508 0.5334)
			(layers "F.Cu" "F.Mask" "F.Paste")
			(net "DDR0_32A_A1")
		)
		(pad "2" smd rect
			(at 0 0.4191 180)
			(size 0.508 0.5334)
			(layers "F.Cu" "F.Mask" "F.Paste")
			(net "DDR_VTT")
		)
		(zone
			(layer "F.Cu")
			(hatch none 0.5)
			(connect_pads
				(clearance 0)
			)
			(min_thickness 0.25)
			(keepout
				(tracks not_allowed)
				(vias allowed)
				(pads allowed)
				(copperpour not_allowed)
				(footprints allowed)
			)
			(placement
				(enabled no)
				(sheetname "")
			)
			(fill
				(thermal_gap 0.5)
				(thermal_bridge_width 0.5)
				(island_removal_mode 0)
			)
			(polygon
				(pts
					(xy 82.7786 28.7274) (xy 82.7786 28.6766) (xy 82.8294 28.6766) (xy 82.8294 28.7274)
				)
			)
		)
	)
	(footprint ""
		(layer "F.Cu")
		(at 25.9588 35.052 -90)
		(property "Reference" "R87"
			(at 0 0 270)
			(layer "F.SilkS")
			(hide yes)
			(effects
				(font
					(size 1.27 1.27)
				)
			)
		)
		(property "Value" "4.75K"
			(at -0.148158 1.3462 0)
			(unlocked yes)
			(layer "F.Fab")
			(hide yes)
			(effects
				(font
					(size 1.27 0.9652)
					(thickness 0.000001)
				)
				(justify left)
			)
		)
		(property "Device Type" "REST4024"
			(at -0.148158 1.3462 0)
			(unlocked yes)
			(layer "F.Fab")
			(hide yes)
			(effects
				(font
					(size 1.27 0.9652)
					(thickness 0.000001)
				)
				(justify left)
			)
		)
		(duplicate_pad_numbers_are_jumpers no)
		(fp_poly
			(pts
				(xy 0.635 1.0668) (xy 0.635 -1.0668) (xy -0.635 -1.0668) (xy -0.635 1.0668)
			)
			(stroke
				(width 0)
				(type default)
			)
			(fill no)
			(layer "F.CrtYd")
		)
		(fp_line
			(start -0.254 0.508)
			(end -0.254 -0.508)
			(stroke
				(width 0.0254)
				(type default)
			)
			(layer "F.Fab")
		)
		(fp_line
			(start 0.254 0.508)
			(end -0.254 0.508)
			(stroke
				(width 0.0254)
				(type default)
			)
			(layer "F.Fab")
		)
		(fp_line
			(start -0.254 -0.508)
			(end 0.254 -0.508)
			(stroke
				(width 0.0254)
				(type default)
			)
			(layer "F.Fab")
		)
		(fp_line
			(start 0.254 -0.508)
			(end 0.254 0.508)
			(stroke
				(width 0.0254)
				(type default)
			)
			(layer "F.Fab")
		)
		(pad "1" smd rect
			(at 0 -0.4191 270)
			(size 0.508 0.5334)
			(layers "F.Cu" "F.Mask" "F.Paste")
			(net "VDD_CORE_PGOOD")
		)
		(pad "2" smd rect
			(at 0 0.4191 270)
			(size 0.508 0.5334)
			(layers "F.Cu" "F.Mask" "F.Paste")
			(net "EXT_3.3V")
		)
		(zone
			(layer "F.Cu")
			(hatch none 0.5)
			(connect_pads
				(clearance 0)
			)
			(min_thickness 0.25)
			(keepout
				(tracks not_allowed)
				(vias allowed)
				(pads allowed)
				(copperpour not_allowed)
				(footprints allowed)
			)
			(placement
				(enabled no)
				(sheetname "")
			)
			(fill
				(thermal_gap 0.5)
				(thermal_bridge_width 0.5)
				(island_removal_mode 0)
			)
			(polygon
				(pts
					(xy 25.9842 35.0774) (xy 25.9334 35.0774) (xy 25.9334 35.0266) (xy 25.9842 35.0266)
				)
			)
		)
	)
)
